# T6G (Grand Teton) — schematic netlist excerpt (pin names and nets, part order shuffled) for the footprints in the layout excerpt that follows; sources: Cadence DE-HDL packaged netlist, KiCad conversion of 04192023_DAF0TMB3IC0_F0TG_MB_C_brd_V02_OCP.brd

R1650  Q_RES  1K 1% CHIP  pkg 0402LF  page 174 : A = PVDD18_S5_P0 ; B = FM_PLD_CPU1_PRSNT_HDT_N
PR221  Q_RES  1.5 1% EMPTY  pkg 0402LF  page 205 : A = SW_PVDDIO_P0_SW1_RC ; B = GND

(kicad_pcb
	(version 20260206)
	(generator "pcbnew")
	(generator_version "10.0")
	(general
		(thickness 1.6)
		(legacy_teardrops no)
	)
	(paper "A4")
	(title_block
		(title "04192023_DAF0TMB3IC0_F0TG_MB_C_brd_V02_OCP.brd")
		(comment 1 "Grand Teton / footprints 330-331 of 8354")
	)
	(layers
		(0 "F.Cu" signal "TOP")
		(4 "In1.Cu" signal "GND")
		(6 "In2.Cu" signal "IN1")
		(8 "In3.Cu" signal "GND1")
		(10 "In4.Cu" signal "IN2")
		(12 "In5.Cu" signal "GND2")
		(14 "In6.Cu" signal "IN3")
		(16 "In7.Cu" signal "GND3")
		(18 "In8.Cu" signal "VCC")
		(20 "In9.Cu" signal "VCC1")
		(22 "In10.Cu" signal "GND4")
		(24 "In11.Cu" signal "IN4")
		(26 "In12.Cu" signal "GND5")
		(28 "In13.Cu" signal "IN5")
		(30 "In14.Cu" signal "GND6")
		(32 "In15.Cu" signal "IN6")
		(34 "In16.Cu" signal "GND7")
		(2 "B.Cu" signal "BOTTOM")
		(9 "F.Adhes" user "F.Adhesive")
		(11 "B.Adhes" user "B.Adhesive")
		(13 "F.Paste" user "Package Geometry/Pastemask Top")
		(15 "B.Paste" user "Package Geometry/Pastemask Bottom")
		(5 "F.SilkS" user "Ref Des/Silkscreen Top")
		(7 "B.SilkS" user "Ref Des/Silkscreen Bottom")
		(1 "F.Mask" user "Board Geometry/Soldermask Top")
		(3 "B.Mask" user "Board Geometry/Soldermask Bottom")
		(17 "Dwgs.User" user "User.Drawings")
		(19 "Cmts.User" user "User.Comments")
		(21 "Eco1.User" user "User.Eco1")
		(23 "Eco2.User" user "User.Eco2")
		(25 "Edge.Cuts" user "Board Geometry/Outline")
		(27 "Margin" user)
		(31 "F.CrtYd" user "Package Geometry/Place Bound Top")
		(29 "B.CrtYd" user "Package Geometry/Place Bound Bottom")
		(35 "F.Fab" user "Ref Des/Assembly Top")
		(33 "B.Fab" user "Ref Des/Assembly Bottom")
	)
	(footprint ""
		(layer "F.Cu")
		(at 219.47251 -131.454144 90)
		(property "Reference" "R1650"
			(at 0 0 90)
			(layer "F.SilkS")
			(hide yes)
			(effects
				(font
					(size 1.27 1.27)
				)
			)
		)
		(property "Value" ""
			(at 0 0 90)
			(layer "F.Fab")
			(effects
				(font
					(size 1.27 1.27)
				)
			)
		)
		(duplicate_pad_numbers_are_jumpers no)
		(fp_line
			(start 0.7874 -0.4064)
			(end 0.7874 0.4064)
			(stroke
				(width 0.1524)
				(type default)
			)
			(layer "F.SilkS")
		)
		(fp_line
			(start -0.7874 -0.4064)
			(end 0.7874 -0.4064)
			(stroke
				(width 0.1524)
				(type default)
			)
			(layer "F.SilkS")
		)
		(fp_line
			(start 0.7874 0.4064)
			(end -0.7874 0.4064)
			(stroke
				(width 0.1524)
				(type default)
			)
			(layer "F.SilkS")
		)
		(fp_line
			(start -0.7874 0.4064)
			(end -0.7874 -0.4064)
			(stroke
				(width 0.1524)
				(type default)
			)
			(layer "F.SilkS")
		)
		(fp_line
			(start -0.12065 -0.305054)
			(end -0.12065 -0.2794)
			(stroke
				(width 0.1)
				(type default)
			)
			(layer "F.Fab")
		)
		(fp_line
			(start -0.67945 -0.305054)
			(end -0.12065 -0.305054)
			(stroke
				(width 0.1)
				(type default)
			)
			(layer "F.Fab")
		)
		(fp_line
			(start 0.67945 -0.3048)
			(end 0.67945 0.3048)
			(stroke
				(width 0.1)
				(type default)
			)
			(layer "F.Fab")
		)
		(fp_line
			(start 0.12065 -0.3048)
			(end 0.67945 -0.3048)
			(stroke
				(width 0.1)
				(type default)
			)
			(layer "F.Fab")
		)
		(fp_line
			(start 0.12065 -0.2794)
			(end 0.12065 -0.3048)
			(stroke
				(width 0.1)
				(type default)
			)
			(layer "F.Fab")
		)
		(fp_line
			(start -0.12065 -0.2794)
			(end 0.12065 -0.2794)
			(stroke
				(width 0.1)
				(type default)
			)
			(layer "F.Fab")
		)
		(fp_line
			(start 0.120396 0.2794)
			(end -0.12065 0.2794)
			(stroke
				(width 0.1)
				(type default)
			)
			(layer "F.Fab")
		)
		(fp_line
			(start -0.12065 0.2794)
			(end -0.12065 0.3048)
			(stroke
				(width 0.1)
				(type default)
			)
			(layer "F.Fab")
		)
		(fp_line
			(start 0.67945 0.3048)
			(end 0.120396 0.3048)
			(stroke
				(width 0.1)
				(type default)
			)
			(layer "F.Fab")
		)
		(fp_line
			(start 0.120396 0.3048)
			(end 0.120396 0.2794)
			(stroke
				(width 0.1)
				(type default)
			)
			(layer "F.Fab")
		)
		(fp_line
			(start -0.12065 0.3048)
			(end -0.67945 0.3048)
			(stroke
				(width 0.1)
				(type default)
			)
			(layer "F.Fab")
		)
		(fp_line
			(start -0.67945 0.3048)
			(end -0.67945 -0.305054)
			(stroke
				(width 0.1)
				(type default)
			)
			(layer "F.Fab")
		)
		(pad "1" smd circle
			(at -0.40005 0 90)
			(size 0 0)
			(layers "F.Cu" "F.Mask" "F.Paste")
			(net "PVDD18_S5_P0")
		)
		(pad "2" smd circle
			(at 0.40005 0 90)
			(size 0 0)
			(layers "F.Cu" "F.Mask" "F.Paste")
			(net "FM_PLD_CPU1_PRSNT_HDT_N")
		)
	)
	(footprint ""
		(layer "F.Cu")
		(at 296.687748 -344.982038 90)
		(property "Reference" "PR221"
			(at 0 0 90)
			(layer "F.SilkS")
			(hide yes)
			(effects
				(font
					(size 1.27 1.27)
				)
			)
		)
		(property "Value" ""
			(at 0 0 90)
			(layer "F.Fab")
			(effects
				(font
					(size 1.27 1.27)
				)
			)
		)
		(duplicate_pad_numbers_are_jumpers no)
		(fp_line
			(start 0.7874 -0.4064)
			(end 0.7874 0.4064)
			(stroke
				(width 0.1524)
				(type default)
			)
			(layer "F.SilkS")
		)
		(fp_line
			(start -0.7874 -0.4064)
			(end 0.7874 -0.4064)
			(stroke
				(width 0.1524)
				(type default)
			)
			(layer "F.SilkS")
		)
		(fp_line
			(start 0.7874 0.4064)
			(end -0.7874 0.4064)
			(stroke
				(width 0.1524)
				(type default)
			)
			(layer "F.SilkS")
		)
		(fp_line
			(start -0.7874 0.4064)
			(end -0.7874 -0.4064)
			(stroke
				(width 0.1524)
				(type default)
			)
			(layer "F.SilkS")
		)
		(fp_line
			(start -0.12065 -0.305054)
			(end -0.12065 -0.2794)
			(stroke
				(width 0.1)
				(type default)
			)
			(layer "F.Fab")
		)
		(fp_line
			(start -0.67945 -0.305054)
			(end -0.12065 -0.305054)
			(stroke
				(width 0.1)
				(type default)
			)
			(layer "F.Fab")
		)
		(fp_line
			(start 0.67945 -0.3048)
			(end 0.67945 0.3048)
			(stroke
				(width 0.1)
				(type default)
			)
			(layer "F.Fab")
		)
		(fp_line
			(start 0.12065 -0.3048)
			(end 0.67945 -0.3048)
			(stroke
				(width 0.1)
				(type default)
			)
			(layer "F.Fab")
		)
		(fp_line
			(start 0.12065 -0.2794)
			(end 0.12065 -0.3048)
			(stroke
				(width 0.1)
				(type default)
			)
			(layer "F.Fab")
		)
		(fp_line
			(start -0.12065 -0.2794)
			(end 0.12065 -0.2794)
			(stroke
				(width 0.1)
				(type default)
			)
			(layer "F.Fab")
		)
		(fp_line
			(start 0.120396 0.2794)
			(end -0.12065 0.2794)
			(stroke
				(width 0.1)
				(type default)
			)
			(layer "F.Fab")
		)
		(fp_line
			(start -0.12065 0.2794)
			(end -0.12065 0.3048)
			(stroke
				(width 0.1)
				(type default)
			)
			(layer "F.Fab")
		)
		(fp_line
			(start 0.67945 0.3048)
			(end 0.120396 0.3048)
			(stroke
				(width 0.1)
				(type default)
			)
			(layer "F.Fab")
		)
		(fp_line
			(start 0.120396 0.3048)
			(end 0.120396 0.2794)
			(stroke
				(width 0.1)
				(type default)
			)
			(layer "F.Fab")
		)
		(fp_line
			(start -0.12065 0.3048)
			(end -0.67945 0.3048)
			(stroke
				(width 0.1)
				(type default)
			)
			(layer "F.Fab")
		)
		(fp_line
			(start -0.67945 0.3048)
			(end -0.67945 -0.305054)
			(stroke
				(width 0.1)
				(type default)
			)
			(layer "F.Fab")
		)
		(pad "1" smd circle
			(at -0.40005 0 90)
			(size 0 0)
			(layers "F.Cu" "F.Mask" "F.Paste")
			(net "SW_PVDDIO_P0_SW1_RC")
		)
		(pad "2" smd circle
			(at 0.40005 0 90)
			(size 0 0)
			(layers "F.Cu" "F.Mask" "F.Paste")
			(net "GND")
		)
	)
)
